(kicad_pcb
	(version 20241229)
	(generator "pcbnew")
	(generator_version "9.0")
	(general
		(thickness 1.711)
		(legacy_teardrops no)
	)
	(paper "A4")
	(title_block
		(title "Antmicro Baseboard for Jetson AGX Thor")
		(date "2026-02-18")
		(rev "1.1.0")
		(company "Antmicro Ltd")
		(comment 1 "www.antmicro.com")
		(comment 9 "footprints 1119-1122 of 1170")
	)
	(layers
		(0 "F.Cu" signal)
		(4 "In1.Cu" signal)
		(6 "In2.Cu" signal)
		(8 "In3.Cu" signal)
		(10 "In4.Cu" jumper)
		(12 "In5.Cu" signal)
		(14 "In6.Cu" signal)
		(16 "In7.Cu" signal)
		(18 "In8.Cu" signal)
		(2 "B.Cu" signal)
		(9 "F.Adhes" user "F.Adhesive")
		(11 "B.Adhes" user "B.Adhesive")
		(13 "F.Paste" user)
		(15 "B.Paste" user)
		(5 "F.SilkS" user "F.Silkscreen")
		(7 "B.SilkS" user "B.Silkscreen")
		(1 "F.Mask" user)
		(3 "B.Mask" user)
		(17 "Dwgs.User" user "User.Drawings")
		(19 "Cmts.User" user "User.Comments")
		(21 "Eco1.User" user "User.Eco1")
		(23 "Eco2.User" user "User.Eco2")
		(25 "Edge.Cuts" user)
		(27 "Margin" user)
		(31 "F.CrtYd" user "F.Courtyard")
		(29 "B.CrtYd" user "B.Courtyard")
		(35 "F.Fab" user)
		(33 "B.Fab" user)
	)
	(footprint "antmicro-footprints:SOT-23-6"
		(layer "B.Cu")
		(at 179.25 91 90)
		(property "Reference" "U61"
			(at -1.75 2 90)
			(layer "B.SilkS")
			(effects
				(font
					(size 0.7 0.7)
					(thickness 0.15)
				)
				(justify right top mirror)
			)
		)
		(property "Value" "LTC4412IS6"
			(at -1.75 -2.693 90)
			(layer "B.Fab")
			(effects
				(font
					(size 0.7 0.7)
					(thickness 0.15)
				)
				(justify right top mirror)
			)
		)
		(property "Datasheet" "https://www.analog.com/media/en/technical-documentation/data-sheets/4412fb.pdf"
			(at 0 0.057 90)
			(layer "B.Fab")
			(hide yes)
			(effects
				(font
					(size 1.27 1.27)
					(thickness 0.15)
				)
				(justify mirror)
			)
		)
		(property "Description" "Ideal diode controller"
			(at 0 0.057 90)
			(layer "B.Fab")
			(hide yes)
			(effects
				(font
					(size 1.27 1.27)
					(thickness 0.15)
				)
				(justify mirror)
			)
		)
		(property "MPN" "LTC4412IS6#TRMPBF"
			(at 0 0 270)
			(unlocked yes)
			(layer "B.Fab")
			(hide yes)
			(effects
				(font
					(size 1 1)
					(thickness 0.15)
				)
				(justify mirror)
			)
		)
		(property "Manufacturer" "Analog Devices"
			(at 0 0 270)
			(unlocked yes)
			(layer "B.Fab")
			(hide yes)
			(effects
				(font
					(size 1 1)
					(thickness 0.15)
				)
				(justify mirror)
			)
		)
		(property "Author" "Antmicro"
			(at 0 0 270)
			(unlocked yes)
			(layer "B.Fab")
			(hide yes)
			(effects
				(font
					(size 1 1)
					(thickness 0.15)
				)
				(justify mirror)
			)
		)
		(property "License" "Apache-2.0"
			(at 0 0 270)
			(unlocked yes)
			(layer "B.Fab")
			(hide yes)
			(effects
				(font
					(size 1 1)
					(thickness 0.15)
				)
				(justify mirror)
			)
		)
		(sheetname "/Power/")
		(sheetfile "power.kicad_sch")
		(attr smd exclude_from_pos_files exclude_from_bom dnp)
		(fp_line
			(start 1.45 -0.643)
			(end 1.45 -0.343)
			(stroke
				(width 0.12)
				(type solid)
			)
			(layer "B.SilkS")
		)
		(fp_line
			(start 1.3 -0.643)
			(end 1.45 -0.643)
			(stroke
				(width 0.12)
				(type solid)
			)
			(layer "B.SilkS")
		)
		(fp_line
			(start -1.45 -0.643)
			(end -1.45 -0.343)
			(stroke
				(width 0.12)
				(type solid)
			)
			(layer "B.SilkS")
		)
		(fp_line
			(start 1.45 0.757)
			(end 1.45 0.457)
			(stroke
				(width 0.12)
				(type solid)
			)
			(layer "B.SilkS")
		)
		(fp_line
			(start 1.3 0.757)
			(end 1.45 0.757)
			(stroke
				(width 0.12)
				(type solid)
			)
			(layer "B.SilkS")
		)
		(fp_line
			(start -1.3 0.757)
			(end -1.45 0.757)
			(stroke
				(width 0.12)
				(type solid)
			)
			(layer "B.SilkS")
		)
		(fp_line
			(start -1.45 0.757)
			(end -1.45 0.457)
			(stroke
				(width 0.12)
				(type solid)
			)
			(layer "B.SilkS")
		)
		(fp_rect
			(start -1.55 1.85)
			(end 1.55 -1.75)
			(stroke
				(width 0.05)
				(type solid)
			)
			(fill no)
			(layer "B.CrtYd")
		)
		(fp_line
			(start 1.5 -0.643)
			(end -1.5 -0.643)
			(stroke
				(width 0.1)
				(type solid)
			)
			(layer "B.Fab")
		)
		(fp_line
			(start -1.5 -0.643)
			(end -1.5 0.757)
			(stroke
				(width 0.1)
				(type solid)
			)
			(layer "B.Fab")
		)
		(fp_line
			(start 1.5 0.757)
			(end 1.5 -0.643)
			(stroke
				(width 0.1)
				(type solid)
			)
			(layer "B.Fab")
		)
		(fp_line
			(start -1.5 0.757)
			(end 1.5 0.757)
			(stroke
				(width 0.1)
				(type solid)
			)
			(layer "B.Fab")
		)
		(fp_text user "."
			(at -1.2 -2.45 90)
			(layer "B.SilkS")
			(effects
				(font
					(size 1 1)
					(thickness 0.15)
				)
				(justify mirror)
			)
		)
		(fp_text user "${REFERENCE}"
			(at -1.75 -4 90)
			(layer "B.Fab")
			(effects
				(font
					(size 0.7 0.7)
					(thickness 0.15)
				)
				(justify right top mirror)
			)
		)
		(fp_text user "License: Apache-2.0"
			(at -1.75 -6.5 90)
			(layer "B.Fab")
			(effects
				(font
					(size 0.7 0.7)
					(thickness 0.15)
				)
				(justify right top mirror)
			)
		)
		(fp_text user "Author: Antmicro"
			(at -1.829 -5.25 90)
			(layer "B.Fab")
			(effects
				(font
					(size 0.7 0.7)
					(thickness 0.15)
				)
				(justify right top mirror)
			)
		)
		(pad "1" smd roundrect
			(at -0.954 -1.1 90)
			(size 0.55 1)
			(layers "B.Cu" "B.Mask" "B.Paste")
			(roundrect_rratio 0.15)
			(net 522 "/Power/USBPD1_HV")
			(pinfunction "IN")
			(pintype "power_in")
		)
		(pad "2" smd roundrect
			(at -0.003 -1.1 90)
			(size 0.55 1)
			(layers "B.Cu" "B.Mask" "B.Paste")
			(roundrect_rratio 0.15)
			(net 1 "GND")
			(pinfunction "GND")
			(pintype "power_in")
		)
		(pad "3" smd roundrect
			(at 0.947 -1.1 90)
			(size 0.55 1)
			(layers "B.Cu" "B.Mask" "B.Paste")
			(roundrect_rratio 0.15)
			(net 1 "GND")
			(pinfunction "CTL")
			(pintype "input")
		)
		(pad "4" smd roundrect
			(at 0.947 1.214 90)
			(size 0.55 1)
			(layers "B.Cu" "B.Mask" "B.Paste")
			(roundrect_rratio 0.15)
			(net 1224 "unconnected-(U61-STAT-Pad4)")
			(pinfunction "STAT")
			(pintype "output+no_connect")
		)
		(pad "5" smd roundrect
			(at -0.003 1.214 90)
			(size 0.55 1)
			(layers "B.Cu" "B.Mask" "B.Paste")
			(roundrect_rratio 0.15)
			(net 1200 "Net-(Q5-G)")
			(pinfunction "GATE")
			(pintype "output")
		)
		(pad "6" smd roundrect
			(at -0.954 1.214 90)
			(size 0.55 1)
			(layers "B.Cu" "B.Mask" "B.Paste")
			(roundrect_rratio 0.15)
			(net 13 "VCC")
			(pinfunction "SENSE")
			(pintype "input")
		)
	)
	(footprint "antmicro-footprints:C_0402_1005Metric"
		(layer "B.Cu")
		(at 230.17 88 180)
		(descr "Capacitor SMD 0402")
		(tags "capacitor SMD 0402")
		(property "Reference" "C153"
			(at 0.87 -0.4 0)
			(layer "B.SilkS")
			(effects
				(font
					(size 0.7 0.7)
					(thickness 0.15)
				)
				(justify left bottom mirror)
			)
		)
		(property "Value" "C_100n_0402"
			(at -1.022927 -2.155213 0)
			(layer "B.Fab")
			(effects
				(font
					(size 0.7 0.7)
					(thickness 0.15)
				)
				(justify left bottom mirror)
			)
		)
		(property "Datasheet" "https://www.murata.com/products/productdetail?partno=GRM155R61H104KE14%23"
			(at 0 0 0)
			(layer "B.Fab")
			(hide yes)
			(effects
				(font
					(size 1.27 1.27)
					(thickness 0.15)
				)
				(justify mirror)
			)
		)
		(property "Description" "SMD Multilayer Ceramic Capacitor, 0.1 µF, 50 V, 0402 [1005 Metric], ± 10%, X5R, GRM Series"
			(at 0 0 0)
			(layer "B.Fab")
			(hide yes)
			(effects
				(font
					(size 1.27 1.27)
					(thickness 0.15)
				)
				(justify mirror)
			)
		)
		(property "MPN" "GRM155R61H104KE14D"
			(at 0 0 0)
			(unlocked yes)
			(layer "B.Fab")
			(hide yes)
			(effects
				(font
					(size 1 1)
					(thickness 0.15)
				)
				(justify mirror)
			)
		)
		(property "Manufacturer" "Murata"
			(at 0 0 0)
			(unlocked yes)
			(layer "B.Fab")
			(hide yes)
			(effects
				(font
					(size 1 1)
					(thickness 0.15)
				)
				(justify mirror)
			)
		)
		(property "Val" "100n"
			(at 0 0 0)
			(unlocked yes)
			(layer "B.Fab")
			(hide yes)
			(effects
				(font
					(size 1 1)
					(thickness 0.15)
				)
				(justify mirror)
			)
		)
		(property "License" "Apache-2.0"
			(at 0 0 0)
			(unlocked yes)
			(layer "B.Fab")
			(hide yes)
			(effects
				(font
					(size 1 1)
					(thickness 0.15)
				)
				(justify mirror)
			)
		)
		(property "Author" "Antmicro"
			(at 0 0 0)
			(unlocked yes)
			(layer "B.Fab")
			(hide yes)
			(effects
				(font
					(size 1 1)
					(thickness 0.15)
				)
				(justify mirror)
			)
		)
		(property "Voltage" "50V"
			(at 0 0 0)
			(unlocked yes)
			(layer "B.Fab")
			(hide yes)
			(effects
				(font
					(size 1 1)
					(thickness 0.15)
				)
				(justify mirror)
			)
		)
		(property "Dielectric" "X5R"
			(at 0 0 0)
			(unlocked yes)
			(layer "B.Fab")
			(hide yes)
			(effects
				(font
					(size 1 1)
					(thickness 0.15)
				)
				(justify mirror)
			)
		)
		(sheetname "/USB DP Alt mode/")
		(sheetfile "usb_dp.kicad_sch")
		(attr smd)
		(fp_poly
			(pts
				(xy -0.925 0.47) (xy 0.925 0.47) (xy 0.925 -0.47) (xy -0.925 -0.47)
			)
			(stroke
				(width 0.05)
				(type default)
			)
			(fill no)
			(layer "B.CrtYd")
		)
		(fp_line
			(start 0.504 0.25)
			(end 0.504 -0.248)
			(stroke
				(width 0.15)
				(type solid)
			)
			(layer "B.Fab")
		)
		(fp_line
			(start 0.504 -0.248)
			(end -0.494 -0.248)
			(stroke
				(width 0.15)
				(type solid)
			)
			(layer "B.Fab")
		)
		(fp_line
			(start -0.494 0.25)
			(end 0.504 0.25)
			(stroke
				(width 0.15)
				(type solid)
			)
			(layer "B.Fab")
		)
		(fp_line
			(start -0.494 -0.248)
			(end -0.494 0.25)
			(stroke
				(width 0.15)
				(type solid)
			)
			(layer "B.Fab")
		)
		(fp_text user "${REFERENCE}"
			(at -0.939 -4.599 0)
			(layer "B.Fab")
			(effects
				(font
					(size 0.7 0.7)
					(thickness 0.15)
				)
				(justify left bottom mirror)
			)
		)
		(fp_text user "Author: Antmicro"
			(at -0.939 -3.399 0)
			(layer "B.Fab")
			(effects
				(font
					(size 0.7 0.7)
					(thickness 0.15)
				)
				(justify left bottom mirror)
			)
		)
		(fp_text user "License: Apache-2.0"
			(at -0.939 -5.799 0)
			(layer "B.Fab")
			(effects
				(font
					(size 0.7 0.7)
					(thickness 0.15)
				)
				(justify left bottom mirror)
			)
		)
		(pad "1" smd roundrect
			(at -0.48 0 180)
			(size 0.59 0.64)
			(layers "B.Cu" "B.Mask" "B.Paste")
			(roundrect_rratio 0.25)
			(net 376 "/USB DP Alt mode/USBC1_VBUS")
			(pintype "passive")
		)
		(pad "2" smd roundrect
			(at 0.48 0 180)
			(size 0.59 0.64)
			(layers "B.Cu" "B.Mask" "B.Paste")
			(roundrect_rratio 0.25)
			(net 1 "GND")
			(pintype "passive")
		)
	)
	(footprint "antmicro-footprints:TP_SMD_0.75mm"
		(layer "B.Cu")
		(at 124.6 136.1 180)
		(property "Reference" "TP39"
			(at -3.23 -0.395 0)
			(layer "B.SilkS")
			(effects
				(font
					(size 0.7 0.7)
					(thickness 0.15)
				)
				(justify left bottom mirror)
			)
		)
		(property "Value" "TP_0.75mm_SMD"
			(at 0 -1.2 0)
			(layer "B.Fab")
			(effects
				(font
					(size 0.7 0.7)
					(thickness 0.15)
				)
				(justify left bottom mirror)
			)
		)
		(property "Description" "SMT test point"
			(at 0 0 0)
			(layer "B.Fab")
			(hide yes)
			(effects
				(font
					(size 1.27 1.27)
					(thickness 0.15)
				)
				(justify mirror)
			)
		)
		(property "MPN" ""
			(at 0 0 0)
			(unlocked yes)
			(layer "B.Fab")
			(hide yes)
			(effects
				(font
					(size 1 1)
					(thickness 0.15)
				)
				(justify mirror)
			)
		)
		(property "Manufacturer" ""
			(at 0 0 0)
			(unlocked yes)
			(layer "B.Fab")
			(hide yes)
			(effects
				(font
					(size 1 1)
					(thickness 0.15)
				)
				(justify mirror)
			)
		)
		(property "Author" "Antmicro"
			(at 0 0 0)
			(unlocked yes)
			(layer "B.Fab")
			(hide yes)
			(effects
				(font
					(size 1 1)
					(thickness 0.15)
				)
				(justify mirror)
			)
		)
		(property "License" "Apache-2.0"
			(at 0 0 0)
			(unlocked yes)
			(layer "B.Fab")
			(hide yes)
			(effects
				(font
					(size 1 1)
					(thickness 0.15)
				)
				(justify mirror)
			)
		)
		(sheetname "/M.2/")
		(sheetfile "m2.kicad_sch")
		(attr exclude_from_pos_files exclude_from_bom)
		(fp_circle
			(center 0 0)
			(end 0.475 0)
			(stroke
				(width 0.05)
				(type default)
			)
			(fill no)
			(layer "B.CrtYd")
		)
		(fp_text user "Author: Antmicro"
			(at -0.4 -3.901 0)
			(layer "B.Fab")
			(effects
				(font
					(size 0.7 0.7)
					(thickness 0.15)
				)
				(justify left bottom mirror)
			)
		)
		(fp_text user "${REFERENCE}"
			(at -0.4 -2.7 0)
			(layer "B.Fab")
			(effects
				(font
					(size 0.7 0.7)
					(thickness 0.15)
				)
				(justify left bottom mirror)
			)
		)
		(fp_text user "License: Apache-2.0"
			(at -0.4 -5.101 0)
			(layer "B.Fab")
			(effects
				(font
					(size 0.7 0.7)
					(thickness 0.15)
				)
				(justify left bottom mirror)
			)
		)
		(pad "1" smd circle
			(at 0 0 180)
			(size 0.75 0.75)
			(layers "B.Cu" "B.Mask")
			(net 257 "/M.2/~{M2_E_ALERT}")
			(pinfunction "1")
			(pintype "passive")
		)
	)
	(footprint "antmicro-footprints:R_0402_1005Metric"
		(layer "B.Cu")
		(at 66.15 63.58 90)
		(descr "Resistor SMD 0402")
		(tags "resistor SMD 0402")
		(property "Reference" "R170"
			(at 0.78 -0.31 90)
			(layer "B.SilkS")
			(effects
				(font
					(size 0.7 0.7)
					(thickness 0.15)
				)
				(justify right top mirror)
			)
		)
		(property "Value" "R_0R_0402"
			(at -1.011843 -1.772046 90)
			(layer "B.Fab")
			(effects
				(font
					(size 0.7 0.7)
					(thickness 0.15)
				)
				(justify right top mirror)
			)
		)
		(property "Datasheet" "https://industrial.panasonic.com/cdbs/www-data/pdf/RDA0000/AOA0000C301.pdf"
			(at 0 0 90)
			(layer "B.Fab")
			(hide yes)
			(effects
				(font
					(size 1.27 1.27)
					(thickness 0.15)
				)
				(justify mirror)
			)
		)
		(property "Description" "SMD Chip Resistor, Jumper, 0 ohm, 100 mW, 0402 [1005 Metric], Thick Film, General Purpose"
			(at 0 0 90)
			(layer "B.Fab")
			(hide yes)
			(effects
				(font
					(size 1.27 1.27)
					(thickness 0.15)
				)
				(justify mirror)
			)
		)
		(property "Manufacturer" "Panasonic"
			(at 0 0 270)
			(unlocked yes)
			(layer "B.Fab")
			(hide yes)
			(effects
				(font
					(size 1 1)
					(thickness 0.15)
				)
				(justify mirror)
			)
		)
		(property "MPN" "ERJ2GE0R00X"
			(at 0 0 270)
			(unlocked yes)
			(layer "B.Fab")
			(hide yes)
			(effects
				(font
					(size 1 1)
					(thickness 0.15)
				)
				(justify mirror)
			)
		)
		(property "Val" "0R"
			(at 0 0 270)
			(unlocked yes)
			(layer "B.Fab")
			(hide yes)
			(effects
				(font
					(size 1 1)
					(thickness 0.15)
				)
				(justify mirror)
			)
		)
		(property "License" "Apache-2.0"
			(at 0 0 270)
			(unlocked yes)
			(layer "B.Fab")
			(hide yes)
			(effects
				(font
					(size 1 1)
					(thickness 0.15)
				)
				(justify mirror)
			)
		)
		(property "Author" "Antmicro"
			(at 0 0 270)
			(unlocked yes)
			(layer "B.Fab")
			(hide yes)
			(effects
				(font
					(size 1 1)
					(thickness 0.15)
				)
				(justify mirror)
			)
		)
		(property "Tolerance" "~"
			(at 0 0 270)
			(unlocked yes)
			(layer "B.Fab")
			(hide yes)
			(effects
				(font
					(size 1 1)
					(thickness 0.15)
				)
				(justify mirror)
			)
		)
		(property "Current" "1A"
			(at 0 0 270)
			(unlocked yes)
			(layer "B.Fab")
			(hide yes)
			(effects
				(font
					(size 1 1)
					(thickness 0.15)
				)
				(justify mirror)
			)
		)
		(sheetname "/CSI/")
		(sheetfile "csi.kicad_sch")
		(attr smd exclude_from_pos_files exclude_from_bom dnp)
		(fp_poly
			(pts
				(xy -0.925 0.47) (xy -0.925 -0.47) (xy 0.925 -0.47) (xy 0.925 0.47)
			)
			(stroke
				(width 0.05)
				(type default)
			)
			(fill no)
			(layer "B.CrtYd")
		)
		(fp_poly
			(pts
				(xy -0.5 0.25) (xy -0.5 -0.25) (xy 0.5 -0.25) (xy 0.5 0.25)
			)
			(stroke
				(width 0.15)
				(type solid)
			)
			(fill no)
			(layer "B.Fab")
		)
		(fp_text user "License: Apache-2.0"
			(at -0.949999 -5.169 90)
			(layer "B.Fab")
			(effects
				(font
					(size 0.7 0.7)
					(thickness 0.15)
				)
				(justify right top mirror)
			)
		)
		(fp_text user "${REFERENCE}"
			(at -0.95 -3.168 90)
			(layer "B.Fab")
			(effects
				(font
					(size 0.7 0.7)
					(thickness 0.15)
				)
				(justify right top mirror)
			)
		)
		(fp_text user "Author: Antmicro"
			(at -0.95 -4.169 90)
			(layer "B.Fab")
			(effects
				(font
					(size 0.7 0.7)
					(thickness 0.15)
				)
				(justify right top mirror)
			)
		)
		(pad "1" smd roundrect
			(at -0.48 0 90)
			(size 0.59 0.64)
			(layers "B.Cu" "B.Mask" "B.Paste")
			(roundrect_rratio 0.25)
			(net 990 "/CSI/CSIB_I2C_VCC")
			(pintype "passive")
		)
		(pad "2" smd roundrect
			(at 0.48 0 90)
			(size 0.59 0.64)
			(layers "B.Cu" "B.Mask" "B.Paste")
			(roundrect_rratio 0.25)
			(net 11 "+1V8")
			(pintype "passive")
		)
	)
)
